(kicad_pcb
	(version 20260206)
	(generator "pcbnew")
	(generator_version "10.0")
	(general
		(thickness 1.6)
		(legacy_teardrops no)
	)
	(paper "A4")
	(title_block
		(title "Wiwynn_Tioga_Pass_MB.brd")
		(comment 1 "Tioga Pass / footprints 4269-4275 of 4770")
	)
	(layers
		(0 "F.Cu" signal "TOP")
		(4 "In1.Cu" signal "L2GND")
		(6 "In2.Cu" signal "L3")
		(8 "In3.Cu" signal "L4GND")
		(10 "In4.Cu" signal "L5")
		(12 "In5.Cu" signal "L6GND")
		(14 "In6.Cu" signal "L7VCC")
		(16 "In7.Cu" signal "L8VCC")
		(18 "In8.Cu" signal "L9GND")
		(20 "In9.Cu" signal "L10")
		(22 "In10.Cu" signal "L11GND")
		(24 "In11.Cu" signal "L12")
		(26 "In12.Cu" signal "L13GND")
		(2 "B.Cu" signal "BOTTOM")
		(9 "F.Adhes" user "F.Adhesive")
		(11 "B.Adhes" user "B.Adhesive")
		(13 "F.Paste" user "Package Geometry/Pastemask Top")
		(15 "B.Paste" user "Package Geometry/Pastemask Bottom")
		(5 "F.SilkS" user "Ref Des/Silkscreen Top")
		(7 "B.SilkS" user "Ref Des/Silkscreen Bottom")
		(1 "F.Mask" user "Board Geometry/Soldermask Top")
		(3 "B.Mask" user "Board Geometry/Soldermask Bottom")
		(17 "Dwgs.User" user "User.Drawings")
		(19 "Cmts.User" user "User.Comments")
		(21 "Eco1.User" user "User.Eco1")
		(23 "Eco2.User" user "User.Eco2")
		(25 "Edge.Cuts" user "Board Geometry/Outline")
		(27 "Margin" user)
		(31 "F.CrtYd" user "Package Geometry/Place Bound Top")
		(29 "B.CrtYd" user "Package Geometry/Place Bound Bottom")
		(35 "F.Fab" user "Ref Des/Assembly Top")
		(33 "B.Fab" user "Ref Des/Assembly Bottom")
	)
	(footprint ""
		(layer "B.Cu")
		(at 369.443 -112.395 -90)
		(property "Reference" "C3M44"
			(at 0 0 90)
			(layer "B.SilkS")
			(hide yes)
			(effects
				(font
					(size 1.27 1.27)
				)
				(justify mirror)
			)
		)
		(property "Value" ""
			(at 0 0 90)
			(layer "B.Fab")
			(effects
				(font
					(size 1.27 1.27)
				)
				(justify mirror)
			)
		)
		(duplicate_pad_numbers_are_jumpers no)
		(fp_poly
			(pts
				(xy -0.3048 -0.1016) (xy -0.3048 0.9906) (xy 0.3048 0.9906) (xy 0.3048 -0.1016)
			)
			(stroke
				(width 0)
				(type default)
			)
			(fill no)
			(layer "B.CrtYd")
		)
		(fp_line
			(start -0.3048 0.9906)
			(end -0.3048 -0.1016)
			(stroke
				(width 0.1)
				(type default)
			)
			(layer "B.Fab")
		)
		(fp_line
			(start 0.3048 0.9906)
			(end -0.3048 0.9906)
			(stroke
				(width 0.1)
				(type default)
			)
			(layer "B.Fab")
		)
		(fp_line
			(start -0.3048 -0.1016)
			(end 0.3048 -0.1016)
			(stroke
				(width 0.1)
				(type default)
			)
			(layer "B.Fab")
		)
		(fp_line
			(start 0.3048 -0.1016)
			(end 0.3048 0.9906)
			(stroke
				(width 0.1)
				(type default)
			)
			(layer "B.Fab")
		)
		(pad "1" smd rect
			(at 0 0 90)
			(size 0.508 0.508)
			(layers "B.Cu" "B.Mask" "B.Paste")
			(net "DMI_CPU0_PCH_RX_DN<0>")
		)
		(pad "2" smd rect
			(at 0 0.889 90)
			(size 0.508 0.508)
			(layers "B.Cu" "B.Mask" "B.Paste")
			(net "DMI_CPU0_PCH_RX_C_DN<0>")
		)
		(zone
			(layer "B.Cu")
			(hatch none 0.5)
			(connect_pads
				(clearance 0)
			)
			(min_thickness 0.25)
			(keepout
				(tracks not_allowed)
				(vias allowed)
				(pads allowed)
				(copperpour not_allowed)
				(footprints allowed)
			)
			(placement
				(enabled no)
				(sheetname "")
			)
			(fill
				(thermal_gap 0.5)
				(thermal_bridge_width 0.5)
				(island_removal_mode 0)
			)
			(polygon
				(pts
					(xy 368.808 -112.141) (xy 368.808 -112.649) (xy 369.189 -112.649) (xy 369.189 -112.141)
				)
			)
		)
		(zone
			(layer "B.Cu")
			(hatch none 0.5)
			(connect_pads
				(clearance 0)
			)
			(min_thickness 0.25)
			(keepout
				(tracks allowed)
				(vias not_allowed)
				(pads allowed)
				(copperpour not_allowed)
				(footprints allowed)
			)
			(placement
				(enabled no)
				(sheetname "")
			)
			(fill
				(thermal_gap 0.5)
				(thermal_bridge_width 0.5)
				(island_removal_mode 0)
			)
			(polygon
				(pts
					(xy 369.189 -112.141) (xy 369.189 -112.649) (xy 368.808 -112.649) (xy 368.808 -112.141)
				)
			)
		)
	)
	(footprint ""
		(layer "B.Cu")
		(at -2.33426 -121.47296 180)
		(property "Reference" "R9M13"
			(at 0 0 0)
			(layer "B.SilkS")
			(hide yes)
			(effects
				(font
					(size 1.27 1.27)
				)
				(justify mirror)
			)
		)
		(property "Value" ""
			(at 0 0 0)
			(layer "B.Fab")
			(effects
				(font
					(size 1.27 1.27)
				)
				(justify mirror)
			)
		)
		(duplicate_pad_numbers_are_jumpers no)
		(fp_rect
			(start 0.2794 -0.1016)
			(end -0.2794 0.9906)
			(stroke
				(width 0)
				(type default)
			)
			(fill no)
			(layer "B.CrtYd")
		)
		(fp_line
			(start 0.2794 0.9906)
			(end -0.2794 0.9906)
			(stroke
				(width 0.1)
				(type default)
			)
			(layer "B.Fab")
		)
		(fp_line
			(start 0.2794 -0.1016)
			(end 0.2794 0.9906)
			(stroke
				(width 0.1)
				(type default)
			)
			(layer "B.Fab")
		)
		(fp_line
			(start -0.2794 0.9906)
			(end -0.2794 -0.1016)
			(stroke
				(width 0.1)
				(type default)
			)
			(layer "B.Fab")
		)
		(fp_line
			(start -0.2794 -0.1016)
			(end 0.2794 -0.1016)
			(stroke
				(width 0.1)
				(type default)
			)
			(layer "B.Fab")
		)
		(pad "1" smd rect
			(at 0 0)
			(size 0.508 0.508)
			(layers "B.Cu" "B.Mask" "B.Paste")
			(net "SMB_PEHPCPU1_STBY_LVC3_R_SDA")
		)
		(pad "2" smd rect
			(at 0 0.889)
			(size 0.508 0.508)
			(layers "B.Cu" "B.Mask" "B.Paste")
			(net "SMB_PEHPCPU1_STBY_LVC3_SDA")
		)
		(zone
			(layer "B.Cu")
			(hatch none 0.5)
			(connect_pads
				(clearance 0)
			)
			(min_thickness 0.25)
			(keepout
				(tracks not_allowed)
				(vias allowed)
				(pads allowed)
				(copperpour not_allowed)
				(footprints allowed)
			)
			(placement
				(enabled no)
				(sheetname "")
			)
			(fill
				(thermal_gap 0.5)
				(thermal_bridge_width 0.5)
				(island_removal_mode 0)
			)
			(polygon
				(pts
					(xy -2.58826 -121.72696) (xy -2.08026 -121.72696) (xy -2.08026 -122.10796) (xy -2.58826 -122.10796)
				)
			)
		)
		(zone
			(layer "B.Cu")
			(hatch none 0.5)
			(connect_pads
				(clearance 0)
			)
			(min_thickness 0.25)
			(keepout
				(tracks allowed)
				(vias not_allowed)
				(pads allowed)
				(copperpour not_allowed)
				(footprints allowed)
			)
			(placement
				(enabled no)
				(sheetname "")
			)
			(fill
				(thermal_gap 0.5)
				(thermal_bridge_width 0.5)
				(island_removal_mode 0)
			)
			(polygon
				(pts
					(xy -2.58826 -121.72696) (xy -2.08026 -121.72696) (xy -2.08026 -122.10796) (xy -2.58826 -122.10796)
				)
			)
		)
	)
	(footprint ""
		(layer "B.Cu")
		(at 16.82242 -108.83392 90)
		(property "Reference" "C9N1"
			(at 0 0 90)
			(layer "B.SilkS")
			(hide yes)
			(effects
				(font
					(size 1.27 1.27)
				)
				(justify mirror)
			)
		)
		(property "Value" ""
			(at 0 0 90)
			(layer "B.Fab")
			(effects
				(font
					(size 1.27 1.27)
				)
				(justify mirror)
			)
		)
		(duplicate_pad_numbers_are_jumpers no)
		(fp_poly
			(pts
				(xy -0.3048 -0.1016) (xy -0.3048 0.9906) (xy 0.3048 0.9906) (xy 0.3048 -0.1016)
			)
			(stroke
				(width 0)
				(type default)
			)
			(fill no)
			(layer "B.CrtYd")
		)
		(fp_line
			(start 0.3048 -0.1016)
			(end 0.3048 0.9906)
			(stroke
				(width 0.1)
				(type default)
			)
			(layer "B.Fab")
		)
		(fp_line
			(start -0.3048 -0.1016)
			(end 0.3048 -0.1016)
			(stroke
				(width 0.1)
				(type default)
			)
			(layer "B.Fab")
		)
		(fp_line
			(start 0.3048 0.9906)
			(end -0.3048 0.9906)
			(stroke
				(width 0.1)
				(type default)
			)
			(layer "B.Fab")
		)
		(fp_line
			(start -0.3048 0.9906)
			(end -0.3048 -0.1016)
			(stroke
				(width 0.1)
				(type default)
			)
			(layer "B.Fab")
		)
		(pad "1" smd rect
			(at 0 0 270)
			(size 0.508 0.508)
			(layers "B.Cu" "B.Mask" "B.Paste")
			(net "P3E_CPU1_PE3_MP_C_TXP<10>")
		)
		(pad "2" smd rect
			(at 0 0.889 270)
			(size 0.508 0.508)
			(layers "B.Cu" "B.Mask" "B.Paste")
			(net "P3E_CPU1_PE3_MP_TXP<10>")
		)
		(zone
			(layer "B.Cu")
			(hatch none 0.5)
			(connect_pads
				(clearance 0)
			)
			(min_thickness 0.25)
			(keepout
				(tracks allowed)
				(vias not_allowed)
				(pads allowed)
				(copperpour not_allowed)
				(footprints allowed)
			)
			(placement
				(enabled no)
				(sheetname "")
			)
			(fill
				(thermal_gap 0.5)
				(thermal_bridge_width 0.5)
				(island_removal_mode 0)
			)
			(polygon
				(pts
					(xy 17.07642 -109.08792) (xy 17.07642 -108.57992) (xy 17.45742 -108.57992) (xy 17.45742 -109.08792)
				)
			)
		)
		(zone
			(layer "B.Cu")
			(hatch none 0.5)
			(connect_pads
				(clearance 0)
			)
			(min_thickness 0.25)
			(keepout
				(tracks not_allowed)
				(vias allowed)
				(pads allowed)
				(copperpour not_allowed)
				(footprints allowed)
			)
			(placement
				(enabled no)
				(sheetname "")
			)
			(fill
				(thermal_gap 0.5)
				(thermal_bridge_width 0.5)
				(island_removal_mode 0)
			)
			(polygon
				(pts
					(xy 17.45742 -109.08792) (xy 17.45742 -108.57992) (xy 17.07642 -108.57992) (xy 17.07642 -109.08792)
				)
			)
		)
	)
	(footprint ""
		(layer "B.Cu")
		(at 456.025758 -31.173674 180)
		(property "Reference" "R8D22"
			(at 0 0 0)
			(layer "B.SilkS")
			(hide yes)
			(effects
				(font
					(size 1.27 1.27)
				)
				(justify mirror)
			)
		)
		(property "Value" ""
			(at 0 0 0)
			(layer "B.Fab")
			(effects
				(font
					(size 1.27 1.27)
				)
				(justify mirror)
			)
		)
		(duplicate_pad_numbers_are_jumpers no)
		(fp_poly
			(pts
				(xy 0.2794 -0.1016) (xy -0.2794 -0.1016) (xy -0.2794 0.9906) (xy 0.2794 0.9906)
			)
			(stroke
				(width 0)
				(type default)
			)
			(fill no)
			(layer "B.CrtYd")
		)
		(fp_line
			(start 0.2794 0.9906)
			(end -0.2794 0.9906)
			(stroke
				(width 0.1)
				(type default)
			)
			(layer "B.Fab")
		)
		(fp_line
			(start 0.2794 -0.1016)
			(end 0.2794 0.9906)
			(stroke
				(width 0.1)
				(type default)
			)
			(layer "B.Fab")
		)
		(fp_line
			(start -0.2794 0.9906)
			(end -0.2794 -0.1016)
			(stroke
				(width 0.1)
				(type default)
			)
			(layer "B.Fab")
		)
		(fp_line
			(start -0.2794 -0.1016)
			(end 0.2794 -0.1016)
			(stroke
				(width 0.1)
				(type default)
			)
			(layer "B.Fab")
		)
		(pad "1" smd rect
			(at 0 0)
			(size 0.508 0.508)
			(layers "B.Cu" "B.Mask" "B.Paste")
			(net "RST_BMC_SRST_R2_N")
		)
		(pad "2" smd rect
			(at 0 0.889)
			(size 0.508 0.508)
			(layers "B.Cu" "B.Mask" "B.Paste")
			(net "FM_TPM_PRES_RST_N")
		)
		(zone
			(layer "B.Cu")
			(hatch none 0.5)
			(connect_pads
				(clearance 0)
			)
			(min_thickness 0.25)
			(keepout
				(tracks not_allowed)
				(vias allowed)
				(pads allowed)
				(copperpour not_allowed)
				(footprints allowed)
			)
			(placement
				(enabled no)
				(sheetname "")
			)
			(fill
				(thermal_gap 0.5)
				(thermal_bridge_width 0.5)
				(island_removal_mode 0)
			)
			(polygon
				(pts
					(xy 455.771758 -31.808674) (xy 456.279758 -31.808674) (xy 456.279758 -31.427674) (xy 455.771758 -31.427674)
				)
			)
		)
		(zone
			(layer "B.Cu")
			(hatch none 0.5)
			(connect_pads
				(clearance 0)
			)
			(min_thickness 0.25)
			(keepout
				(tracks allowed)
				(vias not_allowed)
				(pads allowed)
				(copperpour not_allowed)
				(footprints allowed)
			)
			(placement
				(enabled no)
				(sheetname "")
			)
			(fill
				(thermal_gap 0.5)
				(thermal_bridge_width 0.5)
				(island_removal_mode 0)
			)
			(polygon
				(pts
					(xy 455.771758 -31.427674) (xy 456.279758 -31.427674) (xy 456.279758 -31.808674) (xy 455.771758 -31.808674)
				)
			)
		)
	)
	(footprint ""
		(layer "B.Cu")
		(at 382.905 -133.604 90)
		(property "Reference" "C3M27"
			(at 0 0 90)
			(layer "B.SilkS")
			(hide yes)
			(effects
				(font
					(size 1.27 1.27)
				)
				(justify mirror)
			)
		)
		(property "Value" ""
			(at 0 0 90)
			(layer "B.Fab")
			(effects
				(font
					(size 1.27 1.27)
				)
				(justify mirror)
			)
		)
		(duplicate_pad_numbers_are_jumpers no)
		(fp_poly
			(pts
				(xy -0.3048 -0.1016) (xy -0.3048 0.9906) (xy 0.3048 0.9906) (xy 0.3048 -0.1016)
			)
			(stroke
				(width 0)
				(type default)
			)
			(fill no)
			(layer "B.CrtYd")
		)
		(fp_line
			(start 0.3048 -0.1016)
			(end 0.3048 0.9906)
			(stroke
				(width 0.1)
				(type default)
			)
			(layer "B.Fab")
		)
		(fp_line
			(start -0.3048 -0.1016)
			(end 0.3048 -0.1016)
			(stroke
				(width 0.1)
				(type default)
			)
			(layer "B.Fab")
		)
		(fp_line
			(start 0.3048 0.9906)
			(end -0.3048 0.9906)
			(stroke
				(width 0.1)
				(type default)
			)
			(layer "B.Fab")
		)
		(fp_line
			(start -0.3048 0.9906)
			(end -0.3048 -0.1016)
			(stroke
				(width 0.1)
				(type default)
			)
			(layer "B.Fab")
		)
		(pad "1" smd rect
			(at 0 0 270)
			(size 0.508 0.508)
			(layers "B.Cu" "B.Mask" "B.Paste")
			(net "P1V05_PCH_STBY_VCCA_XTAL")
		)
		(pad "2" smd rect
			(at 0 0.889 270)
			(size 0.508 0.508)
			(layers "B.Cu" "B.Mask" "B.Paste")
			(net "GND")
		)
		(zone
			(layer "B.Cu")
			(hatch none 0.5)
			(connect_pads
				(clearance 0)
			)
			(min_thickness 0.25)
			(keepout
				(tracks allowed)
				(vias not_allowed)
				(pads allowed)
				(copperpour not_allowed)
				(footprints allowed)
			)
			(placement
				(enabled no)
				(sheetname "")
			)
			(fill
				(thermal_gap 0.5)
				(thermal_bridge_width 0.5)
				(island_removal_mode 0)
			)
			(polygon
				(pts
					(xy 383.159 -133.858) (xy 383.159 -133.35) (xy 383.54 -133.35) (xy 383.54 -133.858)
				)
			)
		)
		(zone
			(layer "B.Cu")
			(hatch none 0.5)
			(connect_pads
				(clearance 0)
			)
			(min_thickness 0.25)
			(keepout
				(tracks not_allowed)
				(vias allowed)
				(pads allowed)
				(copperpour not_allowed)
				(footprints allowed)
			)
			(placement
				(enabled no)
				(sheetname "")
			)
			(fill
				(thermal_gap 0.5)
				(thermal_bridge_width 0.5)
				(island_removal_mode 0)
			)
			(polygon
				(pts
					(xy 383.54 -133.858) (xy 383.54 -133.35) (xy 383.159 -133.35) (xy 383.159 -133.858)
				)
			)
		)
	)
	(footprint ""
		(layer "B.Cu")
		(at 14.445488 -80.7847)
		(property "Reference" "Q1W5"
			(at 0.229362 -1.2065 0)
			(unlocked yes)
			(layer "B.SilkS")
			(effects
				(font
					(size 0.4064 0.254)
					(thickness 0.1524)
				)
				(justify left mirror)
			)
		)
		(property "Value" ""
			(at 0 0 0)
			(layer "B.Fab")
			(effects
				(font
					(size 1.27 1.27)
				)
				(justify mirror)
			)
		)
		(duplicate_pad_numbers_are_jumpers no)
		(fp_line
			(start -1.778 -0.5715)
			(end -1.778 0.3175)
			(stroke
				(width 0.1524)
				(type default)
			)
			(layer "B.SilkS")
		)
		(fp_line
			(start -1.778 2.4765)
			(end -1.778 1.5875)
			(stroke
				(width 0.1524)
				(type default)
			)
			(layer "B.SilkS")
		)
		(fp_line
			(start -0.9525 -0.5715)
			(end -1.778 -0.5715)
			(stroke
				(width 0.1524)
				(type default)
			)
			(layer "B.SilkS")
		)
		(fp_line
			(start -0.9525 2.4765)
			(end -1.778 2.4765)
			(stroke
				(width 0.1524)
				(type default)
			)
			(layer "B.SilkS")
		)
		(fp_line
			(start -0.381 0.635)
			(end -0.381 1.27)
			(stroke
				(width 0.1524)
				(type default)
			)
			(layer "B.SilkS")
		)
		(fp_circle
			(center 0.9525 -0.9271)
			(end 1.0795 -0.9271)
			(stroke
				(width 0.254)
				(type default)
			)
			(fill no)
			(layer "B.SilkS")
		)
		(fp_poly
			(pts
				(xy -1.778 2.4765) (xy -0.381 2.4765) (xy -0.381 -0.5715) (xy -1.778 -0.5715)
			)
			(stroke
				(width 0)
				(type default)
			)
			(fill no)
			(layer "B.CrtYd")
		)
		(fp_line
			(start -1.778 -0.5715)
			(end -0.381 -0.5715)
			(stroke
				(width 0.1)
				(type default)
			)
			(layer "B.Fab")
		)
		(fp_line
			(start -1.778 2.4765)
			(end -1.778 -0.5715)
			(stroke
				(width 0.1)
				(type default)
			)
			(layer "B.Fab")
		)
		(fp_line
			(start -0.381 -0.5715)
			(end -0.381 2.4765)
			(stroke
				(width 0.1)
				(type default)
			)
			(layer "B.Fab")
		)
		(fp_line
			(start -0.381 2.4765)
			(end -1.778 2.4765)
			(stroke
				(width 0.1)
				(type default)
			)
			(layer "B.Fab")
		)
		(fp_circle
			(center 0.9525 -0.9271)
			(end 1.0795 -0.9271)
			(stroke
				(width 0.254)
				(type default)
			)
			(fill no)
			(layer "B.Fab")
		)
		(pad "1" smd rect
			(at 0 0 180)
			(size 1.143 0.508)
			(layers "B.Cu" "B.Mask" "B.Paste")
			(net "A_HSC_HIGH_EN")
		)
		(pad "2" smd rect
			(at 0 1.905 180)
			(size 1.143 0.508)
			(layers "B.Cu" "B.Mask" "B.Paste")
			(net "GND")
		)
		(pad "3" smd rect
			(at -2.159 0.9525 180)
			(size 1.143 0.508)
			(layers "B.Cu" "B.Mask" "B.Paste")
			(net "A_HSC_LOW_GATE")
		)
	)
	(footprint ""
		(layer "B.Cu")
		(at 334.264 -45.974 180)
		(property "Reference" "C3R4"
			(at -3.14833 3.429 270)
			(unlocked yes)
			(layer "B.SilkS")
			(effects
				(font
					(size 0.7874 0.5842)
					(thickness 0.1524)
				)
				(justify mirror)
			)
		)
		(property "Value" ""
			(at 0 0 0)
			(layer "B.Fab")
			(effects
				(font
					(size 1.27 1.27)
				)
				(justify mirror)
			)
		)
		(duplicate_pad_numbers_are_jumpers no)
		(fp_line
			(start 2.563114 1.633728)
			(end 1.6002 1.633728)
			(stroke
				(width 0.1524)
				(type default)
			)
			(layer "B.SilkS")
		)
		(fp_line
			(start 2.563114 -1.616456)
			(end 2.563114 1.633728)
			(stroke
				(width 0.1524)
				(type default)
			)
			(layer "B.SilkS")
		)
		(fp_line
			(start 2.286 7.366)
			(end 2.286 1.632712)
			(stroke
				(width 0.1524)
				(type default)
			)
			(layer "B.SilkS")
		)
		(fp_line
			(start 2.286 7.366)
			(end 1.60147 7.366)
			(stroke
				(width 0.1524)
				(type default)
			)
			(layer "B.SilkS")
		)
		(fp_line
			(start 1.6002 -1.616456)
			(end 2.563114 -1.616456)
			(stroke
				(width 0.1524)
				(type default)
			)
			(layer "B.SilkS")
		)
		(fp_line
			(start -1.6002 -1.616456)
			(end -2.504948 -1.616456)
			(stroke
				(width 0.1524)
				(type default)
			)
			(layer "B.SilkS")
		)
		(fp_line
			(start -2.286 7.366)
			(end -1.600708 7.366)
			(stroke
				(width 0.1524)
				(type default)
			)
			(layer "B.SilkS")
		)
		(fp_line
			(start -2.286 7.366)
			(end -2.286 1.63195)
			(stroke
				(width 0.1524)
				(type default)
			)
			(layer "B.SilkS")
		)
		(fp_line
			(start -2.504948 1.633728)
			(end -1.6002 1.633728)
			(stroke
				(width 0.1524)
				(type default)
			)
			(layer "B.SilkS")
		)
		(fp_line
			(start -2.504948 -1.616456)
			(end -2.504948 1.633728)
			(stroke
				(width 0.1524)
				(type default)
			)
			(layer "B.SilkS")
		)
		(fp_rect
			(start 2.286 7.366)
			(end -2.286 -0.254)
			(stroke
				(width 0)
				(type default)
			)
			(fill no)
			(layer "B.CrtYd")
		)
		(fp_line
			(start 2.286 7.366)
			(end 2.286 -0.254)
			(stroke
				(width 0.1)
				(type default)
			)
			(layer "B.Fab")
		)
		(fp_line
			(start 2.286 -0.254)
			(end -2.286 -0.254)
			(stroke
				(width 0.1)
				(type default)
			)
			(layer "B.Fab")
		)
		(fp_line
			(start -2.286 7.366)
			(end 2.286 7.366)
			(stroke
				(width 0.1)
				(type default)
			)
			(layer "B.Fab")
		)
		(fp_line
			(start -2.286 -0.254)
			(end -2.286 7.366)
			(stroke
				(width 0.1)
				(type default)
			)
			(layer "B.Fab")
		)
		(pad "1" smd rect
			(at 0 0)
			(size 2.54 3.048)
			(layers "B.Cu" "B.Mask" "B.Paste")
			(net "PVCCMCP_CPU0")
		)
		(pad "2" smd rect
			(at 0 7.112)
			(size 2.54 3.048)
			(layers "B.Cu" "B.Mask" "B.Paste")
			(net "GND")
		)
	)
)
